(kicad_pcb
	(version 20241229)
	(generator "pcbnew")
	(generator_version "9.0")
	(general
		(thickness 1.552)
		(legacy_teardrops no)
	)
	(paper "A4")
	(title_block
		(date "2023-07-25")
		(rev "1.1.4")
		(comment 9 "footprints 73-74 of 379")
	)
	(layers
		(0 "F.Cu" signal)
		(4 "In1.Cu" signal)
		(6 "In2.Cu" signal)
		(8 "In3.Cu" signal)
		(10 "In4.Cu" signal)
		(12 "In5.Cu" signal)
		(14 "In6.Cu" signal)
		(2 "B.Cu" signal)
		(9 "F.Adhes" user "F.Adhesive")
		(11 "B.Adhes" user "B.Adhesive")
		(13 "F.Paste" user)
		(15 "B.Paste" user)
		(5 "F.SilkS" user "F.Silkscreen")
		(7 "B.SilkS" user "B.Silkscreen")
		(1 "F.Mask" user)
		(3 "B.Mask" user)
		(17 "Dwgs.User" user "User.Drawings")
		(19 "Cmts.User" user "User.Comments")
		(21 "Eco1.User" user "User.Eco1")
		(23 "Eco2.User" user "User.Eco2")
		(25 "Edge.Cuts" user)
		(27 "Margin" user)
		(31 "F.CrtYd" user "F.Courtyard")
		(29 "B.CrtYd" user "B.Courtyard")
		(35 "F.Fab" user)
		(33 "B.Fab" user)
	)
	(footprint "antmicro-footprints:R_0402_1005Metric"
		(layer "F.Cu")
		(at 133.75 116.75 90)
		(descr "Resistor SMD 0402")
		(tags "resistor SMD 0402")
		(property "Reference" "R127"
			(at 0.71 0.73 90)
			(layer "F.SilkS")
			(effects
				(font
					(size 0.65 0.65)
					(thickness 0.15)
				)
				(justify left bottom)
			)
		)
		(property "Value" "R_0R_0402"
			(at 0 1.4 90)
			(layer "F.Fab")
			(hide yes)
			(effects
				(font
					(size 0.7 0.7)
					(thickness 0.15)
				)
				(justify left bottom)
			)
		)
		(property "Datasheet" "https://industrial.panasonic.com/cdbs/www-data/pdf/RDA0000/AOA0000C301.pdf"
			(at 0 0 90)
			(layer "F.Fab")
			(hide yes)
			(effects
				(font
					(size 1.27 1.27)
					(thickness 0.15)
				)
			)
		)
		(property "Description" "SMD Chip Resistor, Jumper, 0 ohm, 100 mW, 0402 [1005 Metric], Thick Film, General Purpose"
			(at 0 0 90)
			(layer "F.Fab")
			(hide yes)
			(effects
				(font
					(size 1.27 1.27)
					(thickness 0.15)
				)
			)
		)
		(property "Author" "Antmicro"
			(at 250.5 -17 0)
			(layer "F.Fab")
			(hide yes)
			(effects
				(font
					(size 1 1)
					(thickness 0.15)
				)
			)
		)
		(property "Current" "1A"
			(at 250.5 -17 0)
			(layer "F.Fab")
			(hide yes)
			(effects
				(font
					(size 1 1)
					(thickness 0.15)
				)
			)
		)
		(property "License" "Apache-2.0"
			(at 250.5 -17 0)
			(layer "F.Fab")
			(hide yes)
			(effects
				(font
					(size 1 1)
					(thickness 0.15)
				)
			)
		)
		(property "MPN" "ERJ2GE0R00X"
			(at 250.5 -17 0)
			(layer "F.Fab")
			(hide yes)
			(effects
				(font
					(size 1 1)
					(thickness 0.15)
				)
			)
		)
		(property "Manufacturer" "Panasonic"
			(at 250.5 -17 0)
			(layer "F.Fab")
			(hide yes)
			(effects
				(font
					(size 1 1)
					(thickness 0.15)
				)
			)
		)
		(property "Tolerance" "~"
			(at 250.5 -17 0)
			(layer "F.Fab")
			(hide yes)
			(effects
				(font
					(size 1 1)
					(thickness 0.15)
				)
			)
		)
		(property "Val" "0R"
			(at 250.5 -17 0)
			(layer "F.Fab")
			(hide yes)
			(effects
				(font
					(size 1 1)
					(thickness 0.15)
				)
			)
		)
		(sheetname "/Peripherals/")
		(sheetfile "peripherals.kicad_sch")
		(attr smd)
		(fp_rect
			(start -0.925 -0.47)
			(end 0.925 0.47)
			(stroke
				(width 0.05)
				(type default)
			)
			(fill no)
			(layer "F.CrtYd")
		)
		(fp_rect
			(start -0.5 -0.25)
			(end 0.5 0.25)
			(stroke
				(width 0.15)
				(type solid)
			)
			(fill no)
			(layer "F.Fab")
		)
		(fp_text user "${REFERENCE}"
			(at -0.95 3.168 90)
			(layer "F.Fab")
			(effects
				(font
					(size 0.7 0.7)
					(thickness 0.15)
				)
				(justify left bottom)
			)
		)
		(fp_text user "License: Apache-2.0"
			(at -0.95 5.169 90)
			(layer "F.Fab")
			(effects
				(font
					(size 0.7 0.7)
					(thickness 0.15)
				)
				(justify left bottom)
			)
		)
		(fp_text user "Author: Antmicro"
			(at -0.95 4.169 90)
			(layer "F.Fab")
			(effects
				(font
					(size 0.7 0.7)
					(thickness 0.15)
				)
				(justify left bottom)
			)
		)
		(pad "1" smd roundrect
			(at -0.48 0 90)
			(size 0.59 0.64)
			(layers "F.Cu" "F.Mask" "F.Paste")
			(roundrect_rratio 0.25)
			(net 347 "Net-(J6-Pad42)")
			(pintype "passive")
		)
		(pad "2" smd roundrect
			(at 0.48 0 90)
			(size 0.59 0.64)
			(layers "F.Cu" "F.Mask" "F.Paste")
			(roundrect_rratio 0.25)
			(net 371 "FCC2_SCL2")
			(pintype "passive")
		)
	)
	(footprint "antmicro-footprints:Conn_JST_SH_1x4_SM04B-SRSS-TB-LF-SN"
		(layer "F.Cu")
		(at 172.3 72.15 90)
		(property "Reference" "J8"
			(at 3.36 -2.07 180)
			(layer "F.SilkS")
			(effects
				(font
					(size 0.7 0.7)
					(thickness 0.15)
				)
				(justify left bottom)
			)
		)
		(property "Value" "SM04B-SRSS-TB-LF-SN"
			(at 0 3.9 90)
			(layer "F.Fab")
			(effects
				(font
					(size 0.7 0.7)
					(thickness 0.15)
				)
				(justify left bottom)
			)
		)
		(property "Datasheet" "https://www.jst-mfg.com/product/pdf/eng/eSH.pdf"
			(at 0 0 90)
			(layer "F.Fab")
			(hide yes)
			(effects
				(font
					(size 1.27 1.27)
					(thickness 0.15)
				)
			)
		)
		(property "Description" "Pin Header, Right Angle, Wire-to-Board, 1 mm, 1 Rows, 4 Contacts, Surface Mount Right Angle, SH"
			(at 0 0 90)
			(layer "F.Fab")
			(hide yes)
			(effects
				(font
					(size 1.27 1.27)
					(thickness 0.15)
				)
			)
		)
		(property "Author" "Antmicro"
			(at 244.45 -100.15 0)
			(layer "F.Fab")
			(hide yes)
			(effects
				(font
					(size 1 1)
					(thickness 0.15)
				)
			)
		)
		(property "License" "Apache-2.0"
			(at 244.45 -100.15 0)
			(layer "F.Fab")
			(hide yes)
			(effects
				(font
					(size 1 1)
					(thickness 0.15)
				)
			)
		)
		(property "MPN" "SM04B-SRSS-TB(LF)(SN)"
			(at 244.45 -100.15 0)
			(layer "F.Fab")
			(hide yes)
			(effects
				(font
					(size 1 1)
					(thickness 0.15)
				)
			)
		)
		(property "Manufacturer" "JST Automotive Connectors"
			(at 244.45 -100.15 0)
			(layer "F.Fab")
			(hide yes)
			(effects
				(font
					(size 1 1)
					(thickness 0.15)
				)
			)
		)
		(sheetname "/Peripherals/")
		(sheetfile "peripherals.kicad_sch")
		(attr smd)
		(fp_line
			(start 3.2 -2)
			(end 3.2 0.6)
			(stroke
				(width 0.15)
				(type solid)
			)
			(layer "F.SilkS")
		)
		(fp_line
			(start 2 -2)
			(end 3.2 -2)
			(stroke
				(width 0.15)
				(type solid)
			)
			(layer "F.SilkS")
		)
		(fp_line
			(start -2 -2)
			(end -3.2 -2)
			(stroke
				(width 0.15)
				(type solid)
			)
			(layer "F.SilkS")
		)
		(fp_line
			(start -3.2 -2)
			(end -3.2 0.6)
			(stroke
				(width 0.15)
				(type solid)
			)
			(layer "F.SilkS")
		)
		(fp_line
			(start -2 2.6)
			(end 2 2.6)
			(stroke
				(width 0.15)
				(type solid)
			)
			(layer "F.SilkS")
		)
		(fp_circle
			(center -2.1 -2.5)
			(end -2.05 -2.5)
			(stroke
				(width 0.15)
				(type solid)
			)
			(fill yes)
			(layer "F.SilkS")
		)
		(fp_rect
			(start -3.65 -3.14)
			(end 3.65 2.9)
			(stroke
				(width 0.05)
				(type solid)
			)
			(fill no)
			(layer "F.CrtYd")
		)
		(fp_rect
			(start -3 -2.475)
			(end 3 2.475)
			(stroke
				(width 0.15)
				(type solid)
			)
			(fill no)
			(layer "F.Fab")
		)
		(fp_text user "${REFERENCE}"
			(at -4 8.28 90)
			(layer "F.Fab")
			(effects
				(font
					(size 0.7 0.7)
					(thickness 0.15)
				)
				(justify left bottom)
			)
		)
		(fp_text user "License: Apache-2.0"
			(at -4 5.88 90)
			(layer "F.Fab")
			(effects
				(font
					(size 0.7 0.7)
					(thickness 0.15)
				)
				(justify left bottom)
			)
		)
		(fp_text user "Author: Antmicro"
			(at -4 7.08 90)
			(layer "F.Fab")
			(effects
				(font
					(size 0.7 0.7)
					(thickness 0.15)
				)
				(justify left bottom)
			)
		)
		(pad "1" smd roundrect
			(at -1.5 -2.12 270)
			(size 0.6 1.55)
			(layers "F.Cu" "F.Mask" "F.Paste")
			(roundrect_rratio 0.25)
			(net 1 "GND")
			(pintype "passive")
		)
		(pad "2" smd roundrect
			(at -0.5 -2.12 270)
			(size 0.6 1.55)
			(layers "F.Cu" "F.Mask" "F.Paste")
			(roundrect_rratio 0.25)
			(net 310 "/Peripherals/QWIIC_3V3")
			(pintype "passive")
		)
		(pad "3" smd roundrect
			(at 0.5 -2.12 270)
			(size 0.6 1.55)
			(layers "F.Cu" "F.Mask" "F.Paste")
			(roundrect_rratio 0.25)
			(net 312 "Net-(J8-Pad3)")
			(pintype "passive")
		)
		(pad "4" smd roundrect
			(at 1.5 -2.12 270)
			(size 0.6 1.55)
			(layers "F.Cu" "F.Mask" "F.Paste")
			(roundrect_rratio 0.25)
			(net 313 "Net-(J8-Pad4)")
			(pintype "passive")
		)
		(pad "MP" smd roundrect
			(at -2.8 1.755 90)
			(size 1.2 1.8)
			(layers "F.Cu" "F.Mask" "F.Paste")
			(roundrect_rratio 0.25)
			(net 1 "GND")
			(pintype "passive")
		)
		(pad "MP" smd roundrect
			(at 2.8 1.755 90)
			(size 1.2 1.8)
			(layers "F.Cu" "F.Mask" "F.Paste")
			(roundrect_rratio 0.25)
			(net 1 "GND")
			(pintype "passive")
		)
	)
)
